# R4006-F1001-03-MECHANICAL ASSEMBLY BOM.xlsx — R4006-F1001-03-BOM (bom)
| Celestica Design Services - Bill oF Material |  |  |  |  |  |  |  |  |  |
| Item | Level | P/N | Revision | Model Name | Description | Category | Quantity | Unit | Material |
| 1 | 1 | R4006-F1001-03 | 03 | R4006-F1001-03 | ASSY,TIME CARD,PVT | ASSY | 1 | SET |  |
| 2 | 2 | A400-00003-FB | 01 | A400-00003-FB | CBL,50 OHM,FREQ RENGE DC-12.4GHZ,SMA STR JACK TO SMB STR PLUG WITH RG-316U CABLE | CABLE | 1 | Each |  |
| 3 | 2 | R4006-G0001-03 | 03 | R4006-G0001-03 | PCA,TIMING CARD,BASE BOARD,MP | PCBA | 1 | Each |  |
| 4 | 2 | R1149-K0002-01 | 01 | R1149-K0002-01 | LABEL,PCBA LABEL,6.4X31.8MM,FB  WEDGE400 | LABEL | 2 | Each |  |
| 5 | 2 | G721-03115-01 | 01 | G721-03115-01 | SCREW,#4-40,PH.PAN ST,ZC,NYLOCK | SCREW | 6 | Each | CARBON STEEL |
| 6 | 2 | A247-00005-FB | 01 | A247-00005-FB | IC,MINIATURE ATOMIC CLOCK,MAC-SA53,1PPS IN/OUT,10MHZ RF OUT,8 PTH PINS+CON 20 PINS | ATOMIC CLOCK | 1 | Each |  |
| 7 | 2 | G721-03114-01 | 01 | G721-03114-01 | SCREW,#2-56X0.157,PH.PAN ST,ZB,NYLOCK | SCREW | 4 | Each | CARBON STEEL |
| 8 | 2 | R4006-E0010-03 | 01 | R4006-E0010-03 | MECH,TIME CARD,BRACKET | METAL | 1 | Each | SGCC |
| 9 | 2 | R4006-K0010-02 | 01 | R4006-K0010-02 | LBL,COMPLIANCE LABEL,TIME CARD,40MM X 14MM | LABEL | 1 | Each |  |
| 10 | 2 | R4006-TP008-01 | 01 | R4006-TP008-01 | THERMAL PAD,51.8*51.8MM,THICKNESS 0.25MM,CONDUCTIVITY NO LESS THAN 3W/MK | PAD | 1 | Each |  |
| 11 | 2 | A322-00003-FB | 01 | A322-00003-FB | ASM,TIMING BOARD,RCB-F9T,8 PINS,MULTI-BAND GNSS W/ SMB ANTENNA CON | PCBA | 1 | Each |  |
